(kicad_pcb
	(version 20260206)
	(generator "pcbnew")
	(generator_version "10.0")
	(general
		(thickness 1.6)
		(legacy_teardrops no)
	)
	(paper "A4")
	(title_block
		(title "01162023_DA0F0TEBIF0_F0T_Expander_BD_F_brd_V02_OCP.brd")
		(comment 1 "Grand Teton / footprints 1060-1066 of 9728")
	)
	(layers
		(0 "F.Cu" signal "TOP")
		(4 "In1.Cu" signal "GND")
		(6 "In2.Cu" signal "VCC")
		(8 "In3.Cu" signal "VCC1")
		(10 "In4.Cu" signal "GND1")
		(12 "In5.Cu" signal "IN1")
		(14 "In6.Cu" signal "GND2")
		(16 "In7.Cu" signal "IN2")
		(18 "In8.Cu" signal "GND3")
		(20 "In9.Cu" signal "IN3")
		(22 "In10.Cu" signal "GND4")
		(24 "In11.Cu" signal "IN4")
		(26 "In12.Cu" signal "GND5")
		(28 "In13.Cu" signal "IN5")
		(30 "In14.Cu" signal "GND6")
		(32 "In15.Cu" signal "IN6")
		(34 "In16.Cu" signal "GND7")
		(2 "B.Cu" signal "BOTTOM")
		(9 "F.Adhes" user "F.Adhesive")
		(11 "B.Adhes" user "B.Adhesive")
		(13 "F.Paste" user "Package Geometry/Pastemask Top")
		(15 "B.Paste" user "Package Geometry/Pastemask Bottom")
		(5 "F.SilkS" user "Ref Des/Silkscreen Top")
		(7 "B.SilkS" user "Ref Des/Silkscreen Bottom")
		(1 "F.Mask" user "Board Geometry/Soldermask Top")
		(3 "B.Mask" user "Board Geometry/Soldermask Bottom")
		(17 "Dwgs.User" user "User.Drawings")
		(19 "Cmts.User" user "User.Comments")
		(21 "Eco1.User" user "User.Eco1")
		(23 "Eco2.User" user "User.Eco2")
		(25 "Edge.Cuts" user "Board Geometry/Outline")
		(27 "Margin" user)
		(31 "F.CrtYd" user "Package Geometry/Place Bound Top")
		(29 "B.CrtYd" user "Package Geometry/Place Bound Bottom")
		(35 "F.Fab" user "Ref Des/Assembly Top")
		(33 "B.Fab" user "Ref Des/Assembly Bottom")
	)
	(footprint ""
		(layer "F.Cu")
		(at 230.749094 -174.69358)
		(property "Reference" "R3148"
			(at 0 0 0)
			(layer "F.SilkS")
			(hide yes)
			(effects
				(font
					(size 1.27 1.27)
				)
			)
		)
		(property "Value" ""
			(at 0 0 0)
			(layer "F.Fab")
			(effects
				(font
					(size 1.27 1.27)
				)
			)
		)
		(duplicate_pad_numbers_are_jumpers no)
		(fp_line
			(start -0.7874 -0.4064)
			(end 0.7874 -0.4064)
			(stroke
				(width 0.1524)
				(type default)
			)
			(layer "F.SilkS")
		)
		(fp_line
			(start -0.7874 0.4064)
			(end -0.7874 -0.4064)
			(stroke
				(width 0.1524)
				(type default)
			)
			(layer "F.SilkS")
		)
		(fp_line
			(start 0.7874 -0.4064)
			(end 0.7874 0.4064)
			(stroke
				(width 0.1524)
				(type default)
			)
			(layer "F.SilkS")
		)
		(fp_line
			(start 0.7874 0.4064)
			(end -0.7874 0.4064)
			(stroke
				(width 0.1524)
				(type default)
			)
			(layer "F.SilkS")
		)
		(fp_line
			(start -0.67945 -0.305054)
			(end -0.12065 -0.305054)
			(stroke
				(width 0.1)
				(type default)
			)
			(layer "F.Fab")
		)
		(fp_line
			(start -0.67945 0.3048)
			(end -0.67945 -0.305054)
			(stroke
				(width 0.1)
				(type default)
			)
			(layer "F.Fab")
		)
		(fp_line
			(start -0.12065 -0.305054)
			(end -0.12065 -0.2794)
			(stroke
				(width 0.1)
				(type default)
			)
			(layer "F.Fab")
		)
		(fp_line
			(start -0.12065 -0.2794)
			(end 0.12065 -0.2794)
			(stroke
				(width 0.1)
				(type default)
			)
			(layer "F.Fab")
		)
		(fp_line
			(start -0.12065 0.2794)
			(end -0.12065 0.3048)
			(stroke
				(width 0.1)
				(type default)
			)
			(layer "F.Fab")
		)
		(fp_line
			(start -0.12065 0.3048)
			(end -0.67945 0.3048)
			(stroke
				(width 0.1)
				(type default)
			)
			(layer "F.Fab")
		)
		(fp_line
			(start 0.120396 0.2794)
			(end -0.12065 0.2794)
			(stroke
				(width 0.1)
				(type default)
			)
			(layer "F.Fab")
		)
		(fp_line
			(start 0.120396 0.3048)
			(end 0.120396 0.2794)
			(stroke
				(width 0.1)
				(type default)
			)
			(layer "F.Fab")
		)
		(fp_line
			(start 0.12065 -0.3048)
			(end 0.67945 -0.3048)
			(stroke
				(width 0.1)
				(type default)
			)
			(layer "F.Fab")
		)
		(fp_line
			(start 0.12065 -0.2794)
			(end 0.12065 -0.3048)
			(stroke
				(width 0.1)
				(type default)
			)
			(layer "F.Fab")
		)
		(fp_line
			(start 0.67945 -0.3048)
			(end 0.67945 0.3048)
			(stroke
				(width 0.1)
				(type default)
			)
			(layer "F.Fab")
		)
		(fp_line
			(start 0.67945 0.3048)
			(end 0.120396 0.3048)
			(stroke
				(width 0.1)
				(type default)
			)
			(layer "F.Fab")
		)
		(pad "1" smd circle
			(at -0.40005 0)
			(size 0 0)
			(layers "F.Cu" "F.Mask" "F.Paste")
			(net "ADM1085_ENOUT")
		)
		(pad "2" smd circle
			(at 0.40005 0)
			(size 0 0)
			(layers "F.Cu" "F.Mask" "F.Paste")
			(net "P3V3_AUX")
		)
	)
	(footprint ""
		(layer "F.Cu")
		(at 69.792342 -31.825184 180)
		(property "Reference" "C84"
			(at 0 0 180)
			(layer "F.SilkS")
			(hide yes)
			(effects
				(font
					(size 1.27 1.27)
				)
			)
		)
		(property "Value" ""
			(at 0 0 180)
			(layer "F.Fab")
			(effects
				(font
					(size 1.27 1.27)
				)
			)
		)
		(duplicate_pad_numbers_are_jumpers no)
		(fp_line
			(start 0.299974 0.150114)
			(end -0.299974 0.150114)
			(stroke
				(width 0.1)
				(type default)
			)
			(layer "F.Fab")
		)
		(fp_line
			(start 0.299974 -0.150114)
			(end 0.299974 0.150114)
			(stroke
				(width 0.1)
				(type default)
			)
			(layer "F.Fab")
		)
		(fp_line
			(start -0.299974 0.150114)
			(end -0.299974 -0.150114)
			(stroke
				(width 0.1)
				(type default)
			)
			(layer "F.Fab")
		)
		(fp_line
			(start -0.299974 -0.150114)
			(end 0.299974 -0.150114)
			(stroke
				(width 0.1)
				(type default)
			)
			(layer "F.Fab")
		)
		(pad "1" smd rect
			(at -0.2667 0 180)
			(size 0.3048 0.381)
			(layers "F.Cu" "F.Mask" "F.Paste")
			(net "P5E_PEX0_STN2_TX_DN<38>")
		)
		(pad "2" smd rect
			(at 0.2667 0 180)
			(size 0.3048 0.381)
			(layers "F.Cu" "F.Mask" "F.Paste")
			(net "P5E_PEX0_STN2_TX_C_DN<38>")
		)
	)
	(footprint ""
		(layer "F.Cu")
		(at 214.225378 -42.849038 180)
		(property "Reference" "R590"
			(at 0 0 180)
			(layer "F.SilkS")
			(hide yes)
			(effects
				(font
					(size 1.27 1.27)
				)
			)
		)
		(property "Value" ""
			(at 0 0 180)
			(layer "F.Fab")
			(effects
				(font
					(size 1.27 1.27)
				)
			)
		)
		(duplicate_pad_numbers_are_jumpers no)
		(fp_line
			(start 0.7874 0.4064)
			(end -0.7874 0.4064)
			(stroke
				(width 0.1524)
				(type default)
			)
			(layer "F.SilkS")
		)
		(fp_line
			(start 0.7874 -0.4064)
			(end 0.7874 0.4064)
			(stroke
				(width 0.1524)
				(type default)
			)
			(layer "F.SilkS")
		)
		(fp_line
			(start -0.7874 0.4064)
			(end -0.7874 -0.4064)
			(stroke
				(width 0.1524)
				(type default)
			)
			(layer "F.SilkS")
		)
		(fp_line
			(start -0.7874 -0.4064)
			(end 0.7874 -0.4064)
			(stroke
				(width 0.1524)
				(type default)
			)
			(layer "F.SilkS")
		)
		(fp_line
			(start 0.67945 0.3048)
			(end 0.120396 0.3048)
			(stroke
				(width 0.1)
				(type default)
			)
			(layer "F.Fab")
		)
		(fp_line
			(start 0.67945 -0.3048)
			(end 0.67945 0.3048)
			(stroke
				(width 0.1)
				(type default)
			)
			(layer "F.Fab")
		)
		(fp_line
			(start 0.12065 -0.2794)
			(end 0.12065 -0.3048)
			(stroke
				(width 0.1)
				(type default)
			)
			(layer "F.Fab")
		)
		(fp_line
			(start 0.12065 -0.3048)
			(end 0.67945 -0.3048)
			(stroke
				(width 0.1)
				(type default)
			)
			(layer "F.Fab")
		)
		(fp_line
			(start 0.120396 0.3048)
			(end 0.120396 0.2794)
			(stroke
				(width 0.1)
				(type default)
			)
			(layer "F.Fab")
		)
		(fp_line
			(start 0.120396 0.2794)
			(end -0.12065 0.2794)
			(stroke
				(width 0.1)
				(type default)
			)
			(layer "F.Fab")
		)
		(fp_line
			(start -0.12065 0.3048)
			(end -0.67945 0.3048)
			(stroke
				(width 0.1)
				(type default)
			)
			(layer "F.Fab")
		)
		(fp_line
			(start -0.12065 0.2794)
			(end -0.12065 0.3048)
			(stroke
				(width 0.1)
				(type default)
			)
			(layer "F.Fab")
		)
		(fp_line
			(start -0.12065 -0.2794)
			(end 0.12065 -0.2794)
			(stroke
				(width 0.1)
				(type default)
			)
			(layer "F.Fab")
		)
		(fp_line
			(start -0.12065 -0.305054)
			(end -0.12065 -0.2794)
			(stroke
				(width 0.1)
				(type default)
			)
			(layer "F.Fab")
		)
		(fp_line
			(start -0.67945 0.3048)
			(end -0.67945 -0.305054)
			(stroke
				(width 0.1)
				(type default)
			)
			(layer "F.Fab")
		)
		(fp_line
			(start -0.67945 -0.305054)
			(end -0.12065 -0.305054)
			(stroke
				(width 0.1)
				(type default)
			)
			(layer "F.Fab")
		)
		(pad "1" smd circle
			(at -0.40005 0 180)
			(size 0 0)
			(layers "F.Cu" "F.Mask" "F.Paste")
			(net "P12V_SSD7_R")
		)
		(pad "2" smd circle
			(at 0.40005 0 180)
			(size 0 0)
			(layers "F.Cu" "F.Mask" "F.Paste")
			(net "P12V_SSD7_VIN_P")
		)
	)
	(footprint ""
		(layer "F.Cu")
		(at 36.638484 -108.29544)
		(property "Reference" "C53"
			(at 0 0 0)
			(layer "F.SilkS")
			(hide yes)
			(effects
				(font
					(size 1.27 1.27)
				)
			)
		)
		(property "Value" ""
			(at 0 0 0)
			(layer "F.Fab")
			(effects
				(font
					(size 1.27 1.27)
				)
			)
		)
		(duplicate_pad_numbers_are_jumpers no)
		(fp_line
			(start -0.299974 -0.150114)
			(end 0.299974 -0.150114)
			(stroke
				(width 0.1)
				(type default)
			)
			(layer "F.Fab")
		)
		(fp_line
			(start -0.299974 0.150114)
			(end -0.299974 -0.150114)
			(stroke
				(width 0.1)
				(type default)
			)
			(layer "F.Fab")
		)
		(fp_line
			(start 0.299974 -0.150114)
			(end 0.299974 0.150114)
			(stroke
				(width 0.1)
				(type default)
			)
			(layer "F.Fab")
		)
		(fp_line
			(start 0.299974 0.150114)
			(end -0.299974 0.150114)
			(stroke
				(width 0.1)
				(type default)
			)
			(layer "F.Fab")
		)
		(pad "1" smd rect
			(at -0.2667 0)
			(size 0.3048 0.381)
			(layers "F.Cu" "F.Mask" "F.Paste")
			(net "P5E_PEX0_STN1_TX_DN<21>")
		)
		(pad "2" smd rect
			(at 0.2667 0)
			(size 0.3048 0.381)
			(layers "F.Cu" "F.Mask" "F.Paste")
			(net "P5E_PEX0_STN1_TX_C_DN<21>")
		)
	)
	(footprint ""
		(layer "F.Cu")
		(at 398.493488 -172.004482 -90)
		(property "Reference" "U41"
			(at 1.062482 2.303018 90)
			(unlocked yes)
			(layer "F.SilkS")
			(effects
				(font
					(size 0.7874 0.5842)
					(thickness 0.1524)
				)
				(justify left)
			)
		)
		(property "Value" ""
			(at 0 0 270)
			(layer "F.Fab")
			(effects
				(font
					(size 1.27 1.27)
				)
			)
		)
		(duplicate_pad_numbers_are_jumpers no)
		(fp_line
			(start -2.0574 1.651)
			(end -2.0574 -1.651)
			(stroke
				(width 0.1524)
				(type default)
			)
			(layer "F.SilkS")
		)
		(fp_line
			(start 2.0574 1.651)
			(end -2.0574 1.651)
			(stroke
				(width 0.1524)
				(type default)
			)
			(layer "F.SilkS")
		)
		(fp_line
			(start 0 -1.016)
			(end 0.381 -1.651)
			(stroke
				(width 0.1524)
				(type default)
			)
			(layer "F.SilkS")
		)
		(fp_line
			(start -2.0574 -1.651)
			(end -0.381 -1.651)
			(stroke
				(width 0.1524)
				(type default)
			)
			(layer "F.SilkS")
		)
		(fp_line
			(start -0.381 -1.651)
			(end 0 -1.016)
			(stroke
				(width 0.1524)
				(type default)
			)
			(layer "F.SilkS")
		)
		(fp_line
			(start 0.381 -1.651)
			(end 2.0574 -1.651)
			(stroke
				(width 0.1524)
				(type default)
			)
			(layer "F.SilkS")
		)
		(fp_line
			(start 2.0574 -1.651)
			(end 2.0574 1.651)
			(stroke
				(width 0.1524)
				(type default)
			)
			(layer "F.SilkS")
		)
		(fp_poly
			(pts
				(xy -2.71272 -0.719328) (xy -2.71272 -1.344168) (xy -2.159 -1.016)
			)
			(stroke
				(width 0)
				(type default)
			)
			(fill yes)
			(layer "F.SilkS")
		)
		(fp_line
			(start -0.899922 1.549908)
			(end -0.899922 1.199896)
			(stroke
				(width 0.1)
				(type default)
			)
			(layer "F.Fab")
		)
		(fp_line
			(start 0.899922 1.549908)
			(end -0.899922 1.549908)
			(stroke
				(width 0.1)
				(type default)
			)
			(layer "F.Fab")
		)
		(fp_line
			(start -1.599946 1.199896)
			(end -1.599946 -1.199896)
			(stroke
				(width 0.1)
				(type default)
			)
			(layer "F.Fab")
		)
		(fp_line
			(start -0.899922 1.199896)
			(end -1.599946 1.199896)
			(stroke
				(width 0.1)
				(type default)
			)
			(layer "F.Fab")
		)
		(fp_line
			(start 0.899922 1.199896)
			(end 0.899922 1.549908)
			(stroke
				(width 0.1)
				(type default)
			)
			(layer "F.Fab")
		)
		(fp_line
			(start 1.599946 1.199896)
			(end 0.899922 1.199896)
			(stroke
				(width 0.1)
				(type default)
			)
			(layer "F.Fab")
		)
		(fp_line
			(start -1.599946 -1.199896)
			(end -0.899922 -1.199896)
			(stroke
				(width 0.1)
				(type default)
			)
			(layer "F.Fab")
		)
		(fp_line
			(start -0.899922 -1.199896)
			(end -0.899922 -1.549908)
			(stroke
				(width 0.1)
				(type default)
			)
			(layer "F.Fab")
		)
		(fp_line
			(start 0.899922 -1.199896)
			(end 1.599946 -1.199896)
			(stroke
				(width 0.1)
				(type default)
			)
			(layer "F.Fab")
		)
		(fp_line
			(start 1.599946 -1.199896)
			(end 1.599946 1.199896)
			(stroke
				(width 0.1)
				(type default)
			)
			(layer "F.Fab")
		)
		(fp_line
			(start -0.899922 -1.549908)
			(end 0.899922 -1.549908)
			(stroke
				(width 0.1)
				(type default)
			)
			(layer "F.Fab")
		)
		(fp_line
			(start 0.899922 -1.549908)
			(end 0.899922 -1.199896)
			(stroke
				(width 0.1)
				(type default)
			)
			(layer "F.Fab")
		)
		(fp_poly
			(pts
				(xy -2.71272 -0.719328) (xy -2.71272 -1.344168) (xy -2.159 -1.016)
			)
			(stroke
				(width 0)
				(type default)
			)
			(fill yes)
			(layer "F.Fab")
		)
		(pad "1" smd rect
			(at -1.225042 -0.94996 180)
			(size 0.5588 1.3462)
			(layers "F.Cu" "F.Mask" "F.Paste")
			(net "HP_NIC6_PWRGD_R")
		)
		(pad "2" smd rect
			(at -1.225042 0 180)
			(size 0.5588 1.3462)
			(layers "F.Cu" "F.Mask" "F.Paste")
			(net "RST_NIC6_PERST_R_N")
		)
		(pad "3" smd rect
			(at -1.225042 0.94996 180)
			(size 0.5588 1.3462)
			(layers "F.Cu" "F.Mask" "F.Paste")
			(net "GND")
		)
		(pad "4" smd rect
			(at 1.225042 0.94996 180)
			(size 0.5588 1.3462)
			(layers "F.Cu" "F.Mask" "F.Paste")
			(net "RST_HP_NIC6_N")
		)
		(pad "5" smd rect
			(at 1.225042 -0.94996 180)
			(size 0.5588 1.3462)
			(layers "F.Cu" "F.Mask" "F.Paste")
			(net "P3V3_AUX")
		)
	)
	(footprint ""
		(layer "F.Cu")
		(at 452.1581 -236.029246)
		(property "Reference" "C4441"
			(at 0 0 0)
			(layer "F.SilkS")
			(hide yes)
			(effects
				(font
					(size 1.27 1.27)
				)
			)
		)
		(property "Value" ""
			(at 0 0 0)
			(layer "F.Fab")
			(effects
				(font
					(size 1.27 1.27)
				)
			)
		)
		(duplicate_pad_numbers_are_jumpers no)
		(fp_line
			(start -1.2954 -0.5842)
			(end 1.2954 -0.5842)
			(stroke
				(width 0.1524)
				(type default)
			)
			(layer "F.SilkS")
		)
		(fp_line
			(start -1.2954 0.5842)
			(end -1.2954 -0.5842)
			(stroke
				(width 0.1524)
				(type default)
			)
			(layer "F.SilkS")
		)
		(fp_line
			(start 1.2954 -0.5842)
			(end 1.2954 0.5842)
			(stroke
				(width 0.1524)
				(type default)
			)
			(layer "F.SilkS")
		)
		(fp_line
			(start 1.2954 0.5842)
			(end -1.2954 0.5842)
			(stroke
				(width 0.1524)
				(type default)
			)
			(layer "F.SilkS")
		)
		(fp_line
			(start -1.1938 -0.4064)
			(end -0.8636 -0.4064)
			(stroke
				(width 0.1)
				(type default)
			)
			(layer "F.Fab")
		)
		(fp_line
			(start -1.1938 0.4064)
			(end -1.1938 -0.4064)
			(stroke
				(width 0.1)
				(type default)
			)
			(layer "F.Fab")
		)
		(fp_line
			(start -0.8636 -0.4572)
			(end 0.8636 -0.4572)
			(stroke
				(width 0.1)
				(type default)
			)
			(layer "F.Fab")
		)
		(fp_line
			(start -0.8636 -0.4064)
			(end -0.8636 -0.4572)
			(stroke
				(width 0.1)
				(type default)
			)
			(layer "F.Fab")
		)
		(fp_line
			(start -0.8636 0.4064)
			(end -1.1938 0.4064)
			(stroke
				(width 0.1)
				(type default)
			)
			(layer "F.Fab")
		)
		(fp_line
			(start -0.8636 0.4572)
			(end -0.8636 0.4064)
			(stroke
				(width 0.1)
				(type default)
			)
			(layer "F.Fab")
		)
		(fp_line
			(start 0.8636 -0.4572)
			(end 0.8636 -0.4064)
			(stroke
				(width 0.1)
				(type default)
			)
			(layer "F.Fab")
		)
		(fp_line
			(start 0.8636 -0.4064)
			(end 1.1938 -0.4064)
			(stroke
				(width 0.1)
				(type default)
			)
			(layer "F.Fab")
		)
		(fp_line
			(start 0.8636 0.4064)
			(end 0.8636 0.4572)
			(stroke
				(width 0.1)
				(type default)
			)
			(layer "F.Fab")
		)
		(fp_line
			(start 0.8636 0.4572)
			(end -0.8636 0.4572)
			(stroke
				(width 0.1)
				(type default)
			)
			(layer "F.Fab")
		)
		(fp_line
			(start 1.1938 -0.4064)
			(end 1.1938 0.4064)
			(stroke
				(width 0.1)
				(type default)
			)
			(layer "F.Fab")
		)
		(fp_line
			(start 1.1938 0.4064)
			(end 0.8636 0.4064)
			(stroke
				(width 0.1)
				(type default)
			)
			(layer "F.Fab")
		)
		(pad "1" smd rect
			(at -0.7366 0 270)
			(size 0.7112 0.8128)
			(layers "F.Cu" "F.Mask" "F.Paste")
			(net "P3V3_AUX")
		)
		(pad "2" smd rect
			(at 0.7366 0 270)
			(size 0.7112 0.8128)
			(layers "F.Cu" "F.Mask" "F.Paste")
			(net "GND")
		)
	)
	(footprint ""
		(layer "F.Cu")
		(at 321.678808 -308.323488 135)
		(property "Reference" "R1390"
			(at 0 0 135)
			(layer "F.SilkS")
			(hide yes)
			(effects
				(font
					(size 1.27 1.27)
				)
			)
		)
		(property "Value" ""
			(at 0 0 135)
			(layer "F.Fab")
			(effects
				(font
					(size 1.27 1.27)
				)
			)
		)
		(duplicate_pad_numbers_are_jumpers no)
		(fp_line
			(start 0.787389 -0.406267)
			(end 0.787389 0.406267)
			(stroke
				(width 0.1524)
				(type default)
			)
			(layer "F.SilkS")
		)
		(fp_line
			(start 0.787389 0.406267)
			(end -0.787389 0.406267)
			(stroke
				(width 0.1524)
				(type default)
			)
			(layer "F.SilkS")
		)
		(fp_line
			(start -0.787389 -0.406267)
			(end 0.787389 -0.406267)
			(stroke
				(width 0.1524)
				(type default)
			)
			(layer "F.SilkS")
		)
		(fp_line
			(start -0.787389 0.406267)
			(end -0.787389 -0.406267)
			(stroke
				(width 0.1524)
				(type default)
			)
			(layer "F.SilkS")
		)
		(fp_line
			(start 0.679446 -0.30479)
			(end 0.679446 0.30479)
			(stroke
				(width 0.1)
				(type default)
			)
			(layer "F.Fab")
		)
		(fp_line
			(start 0.120515 -0.30479)
			(end 0.679446 -0.30479)
			(stroke
				(width 0.1)
				(type default)
			)
			(layer "F.Fab")
		)
		(fp_line
			(start 0.120695 -0.279466)
			(end 0.120515 -0.30479)
			(stroke
				(width 0.1)
				(type default)
			)
			(layer "F.Fab")
		)
		(fp_line
			(start 0.679446 0.30479)
			(end 0.120515 0.30479)
			(stroke
				(width 0.1)
				(type default)
			)
			(layer "F.Fab")
		)
		(fp_line
			(start -0.120695 -0.304969)
			(end -0.120695 -0.279466)
			(stroke
				(width 0.1)
				(type default)
			)
			(layer "F.Fab")
		)
		(fp_line
			(start -0.120695 -0.279466)
			(end 0.120695 -0.279466)
			(stroke
				(width 0.1)
				(type default)
			)
			(layer "F.Fab")
		)
		(fp_line
			(start 0.120335 0.279466)
			(end -0.120695 0.279466)
			(stroke
				(width 0.1)
				(type default)
			)
			(layer "F.Fab")
		)
		(fp_line
			(start 0.120515 0.30479)
			(end 0.120335 0.279466)
			(stroke
				(width 0.1)
				(type default)
			)
			(layer "F.Fab")
		)
		(fp_line
			(start -0.679446 -0.305149)
			(end -0.120695 -0.304969)
			(stroke
				(width 0.1)
				(type default)
			)
			(layer "F.Fab")
		)
		(fp_line
			(start -0.120695 0.279466)
			(end -0.120515 0.30479)
			(stroke
				(width 0.1)
				(type default)
			)
			(layer "F.Fab")
		)
		(fp_line
			(start -0.120515 0.30479)
			(end -0.679446 0.30479)
			(stroke
				(width 0.1)
				(type default)
			)
			(layer "F.Fab")
		)
		(fp_line
			(start -0.679446 0.30479)
			(end -0.679446 -0.305149)
			(stroke
				(width 0.1)
				(type default)
			)
			(layer "F.Fab")
		)
		(pad "1" smd circle
			(at -0.40005 0 135)
			(size 0 0)
			(layers "F.Cu" "F.Mask" "F.Paste")
			(net "GND")
		)
		(pad "2" smd circle
			(at 0.40005 0 135)
			(size 0 0)
			(layers "F.Cu" "F.Mask" "F.Paste")
			(net "PEX2_SPARE7")
		)
	)
)
